FILE_TYPE=LIBRARY_PARTS;
primitive 'Q_INDUCTOR4P_12';
  pin
    '4':
      PIN_NUMBER='(4)';
      BIDIRECTIONAL='TRUE';
      INPUT_LOAD='(-0.01,0.01)';
      OUTPUT_LOAD='(1.0,-1.0)';
    '3':
      PIN_NUMBER='(3)';
      BIDIRECTIONAL='TRUE';
      INPUT_LOAD='(-0.01,0.01)';
      OUTPUT_LOAD='(1.0,-1.0)';
    '2':
      PIN_NUMBER='(2)';
      BIDIRECTIONAL='TRUE';
      INPUT_LOAD='(-0.01,0.01)';
      OUTPUT_LOAD='(1.0,-1.0)';
    '1':
      PIN_NUMBER='(1)';
      BIDIRECTIONAL='TRUE';
      INPUT_LOAD='(-0.01,0.01)';
      OUTPUT_LOAD='(1.0,-1.0)';
  end_pin;
  body
    PART_NAME='q_inductor4p_12';
    BODY_NAME='Q_INDUCTOR4P_12';
    PHYS_DES_PREFIX='L';
    CLASS='DISCRETE';
  end_body;
end_primitive;

END.
